# T6G (Grand Teton) — schematic netlist excerpt (pin names and nets, part order shuffled) for the footprints in the layout excerpt that follows; sources: Cadence DE-HDL packaged netlist, KiCad conversion of 04192023_DAF0TMB3IC0_F0TG_MB_C_brd_V02_OCP.brd

C264  Q_CAP  0.1UF 10V 10% X7S  pkg C0201  page 323 : A = P0V9_CPU1_RT0_2A ; B = GND
C286  Q_CAP  10UF 6.3V 20% X6S  pkg C0402  page 323 : A = P0V9_CPU1_RT0_2A ; B = GND
R763  Q_RES  35.7K 1% CHIP  pkg 0402LF  page 89 : A = PD_CHD_CPU0_DIMM_SAA ; B = GND

(kicad_pcb
	(version 20260206)
	(generator "pcbnew")
	(generator_version "10.0")
	(general
		(thickness 1.6)
		(legacy_teardrops no)
	)
	(paper "A4")
	(title_block
		(title "04192023_DAF0TMB3IC0_F0TG_MB_C_brd_V02_OCP.brd")
		(comment 1 "Grand Teton / footprints 6446-6448 of 8354")
	)
	(layers
		(0 "F.Cu" signal "TOP")
		(4 "In1.Cu" signal "GND")
		(6 "In2.Cu" signal "IN1")
		(8 "In3.Cu" signal "GND1")
		(10 "In4.Cu" signal "IN2")
		(12 "In5.Cu" signal "GND2")
		(14 "In6.Cu" signal "IN3")
		(16 "In7.Cu" signal "GND3")
		(18 "In8.Cu" signal "VCC")
		(20 "In9.Cu" signal "VCC1")
		(22 "In10.Cu" signal "GND4")
		(24 "In11.Cu" signal "IN4")
		(26 "In12.Cu" signal "GND5")
		(28 "In13.Cu" signal "IN5")
		(30 "In14.Cu" signal "GND6")
		(32 "In15.Cu" signal "IN6")
		(34 "In16.Cu" signal "GND7")
		(2 "B.Cu" signal "BOTTOM")
		(9 "F.Adhes" user "F.Adhesive")
		(11 "B.Adhes" user "B.Adhesive")
		(13 "F.Paste" user "Package Geometry/Pastemask Top")
		(15 "B.Paste" user "Package Geometry/Pastemask Bottom")
		(5 "F.SilkS" user "Ref Des/Silkscreen Top")
		(7 "B.SilkS" user "Ref Des/Silkscreen Bottom")
		(1 "F.Mask" user "Board Geometry/Soldermask Top")
		(3 "B.Mask" user "Board Geometry/Soldermask Bottom")
		(17 "Dwgs.User" user "User.Drawings")
		(19 "Cmts.User" user "User.Comments")
		(21 "Eco1.User" user "User.Eco1")
		(23 "Eco2.User" user "User.Eco2")
		(25 "Edge.Cuts" user "Board Geometry/Outline")
		(27 "Margin" user)
		(31 "F.CrtYd" user "Package Geometry/Place Bound Top")
		(29 "B.CrtYd" user "Package Geometry/Place Bound Bottom")
		(35 "F.Fab" user "Ref Des/Assembly Top")
		(33 "B.Fab" user "Ref Des/Assembly Bottom")
	)
	(footprint ""
		(layer "B.Cu")
		(at 61.791342 -390.560052 90)
		(property "Reference" "C286"
			(at 0 0 90)
			(layer "B.SilkS")
			(hide yes)
			(effects
				(font
					(size 1.27 1.27)
				)
				(justify mirror)
			)
		)
		(property "Value" ""
			(at 0 0 90)
			(layer "B.Fab")
			(effects
				(font
					(size 1.27 1.27)
				)
				(justify mirror)
			)
		)
		(duplicate_pad_numbers_are_jumpers no)
		(fp_line
			(start 0.7874 -0.4064)
			(end -0.7874 -0.4064)
			(stroke
				(width 0.1524)
				(type default)
			)
			(layer "B.SilkS")
		)
		(fp_line
			(start -0.7874 -0.4064)
			(end -0.7874 0.4064)
			(stroke
				(width 0.1524)
				(type default)
			)
			(layer "B.SilkS")
		)
		(fp_line
			(start 0.7874 0.4064)
			(end 0.7874 -0.4064)
			(stroke
				(width 0.1524)
				(type default)
			)
			(layer "B.SilkS")
		)
		(fp_line
			(start -0.7874 0.4064)
			(end 0.7874 0.4064)
			(stroke
				(width 0.1524)
				(type default)
			)
			(layer "B.SilkS")
		)
		(fp_line
			(start 0.67945 -0.305054)
			(end 0.12065 -0.305054)
			(stroke
				(width 0.1)
				(type default)
			)
			(layer "B.Fab")
		)
		(fp_line
			(start 0.12065 -0.305054)
			(end 0.12065 -0.2794)
			(stroke
				(width 0.1)
				(type default)
			)
			(layer "B.Fab")
		)
		(fp_line
			(start -0.12065 -0.3048)
			(end -0.67945 -0.3048)
			(stroke
				(width 0.1)
				(type default)
			)
			(layer "B.Fab")
		)
		(fp_line
			(start -0.67945 -0.3048)
			(end -0.67945 0.3048)
			(stroke
				(width 0.1)
				(type default)
			)
			(layer "B.Fab")
		)
		(fp_line
			(start 0.12065 -0.2794)
			(end -0.12065 -0.2794)
			(stroke
				(width 0.1)
				(type default)
			)
			(layer "B.Fab")
		)
		(fp_line
			(start -0.12065 -0.2794)
			(end -0.12065 -0.3048)
			(stroke
				(width 0.1)
				(type default)
			)
			(layer "B.Fab")
		)
		(fp_line
			(start 0.12065 0.2794)
			(end 0.12065 0.3048)
			(stroke
				(width 0.1)
				(type default)
			)
			(layer "B.Fab")
		)
		(fp_line
			(start -0.120396 0.2794)
			(end 0.12065 0.2794)
			(stroke
				(width 0.1)
				(type default)
			)
			(layer "B.Fab")
		)
		(fp_line
			(start 0.67945 0.3048)
			(end 0.67945 -0.305054)
			(stroke
				(width 0.1)
				(type default)
			)
			(layer "B.Fab")
		)
		(fp_line
			(start 0.12065 0.3048)
			(end 0.67945 0.3048)
			(stroke
				(width 0.1)
				(type default)
			)
			(layer "B.Fab")
		)
		(fp_line
			(start -0.120396 0.3048)
			(end -0.120396 0.2794)
			(stroke
				(width 0.1)
				(type default)
			)
			(layer "B.Fab")
		)
		(fp_line
			(start -0.67945 0.3048)
			(end -0.120396 0.3048)
			(stroke
				(width 0.1)
				(type default)
			)
			(layer "B.Fab")
		)
		(pad "1" smd circle
			(at 0.40005 0 270)
			(size 0 0)
			(layers "B.Cu" "B.Mask" "B.Paste")
			(net "P0V9_CPU1_RT0_2A")
		)
		(pad "2" smd circle
			(at -0.40005 0 270)
			(size 0 0)
			(layers "B.Cu" "B.Mask" "B.Paste")
			(net "GND")
		)
	)
	(footprint ""
		(layer "B.Cu")
		(at 281.391614 -194.88531 180)
		(property "Reference" "R763"
			(at 0 0 0)
			(layer "B.SilkS")
			(hide yes)
			(effects
				(font
					(size 1.27 1.27)
				)
				(justify mirror)
			)
		)
		(property "Value" ""
			(at 0 0 0)
			(layer "B.Fab")
			(effects
				(font
					(size 1.27 1.27)
				)
				(justify mirror)
			)
		)
		(duplicate_pad_numbers_are_jumpers no)
		(fp_line
			(start 0.7874 0.4064)
			(end 0.7874 -0.4064)
			(stroke
				(width 0.1524)
				(type default)
			)
			(layer "B.SilkS")
		)
		(fp_line
			(start 0.7874 -0.4064)
			(end -0.7874 -0.4064)
			(stroke
				(width 0.1524)
				(type default)
			)
			(layer "B.SilkS")
		)
		(fp_line
			(start -0.7874 0.4064)
			(end 0.7874 0.4064)
			(stroke
				(width 0.1524)
				(type default)
			)
			(layer "B.SilkS")
		)
		(fp_line
			(start -0.7874 -0.4064)
			(end -0.7874 0.4064)
			(stroke
				(width 0.1524)
				(type default)
			)
			(layer "B.SilkS")
		)
		(fp_line
			(start 0.67945 0.3048)
			(end 0.67945 -0.305054)
			(stroke
				(width 0.1)
				(type default)
			)
			(layer "B.Fab")
		)
		(fp_line
			(start 0.67945 -0.305054)
			(end 0.12065 -0.305054)
			(stroke
				(width 0.1)
				(type default)
			)
			(layer "B.Fab")
		)
		(fp_line
			(start 0.12065 0.3048)
			(end 0.67945 0.3048)
			(stroke
				(width 0.1)
				(type default)
			)
			(layer "B.Fab")
		)
		(fp_line
			(start 0.12065 0.2794)
			(end 0.12065 0.3048)
			(stroke
				(width 0.1)
				(type default)
			)
			(layer "B.Fab")
		)
		(fp_line
			(start 0.12065 -0.2794)
			(end -0.12065 -0.2794)
			(stroke
				(width 0.1)
				(type default)
			)
			(layer "B.Fab")
		)
		(fp_line
			(start 0.12065 -0.305054)
			(end 0.12065 -0.2794)
			(stroke
				(width 0.1)
				(type default)
			)
			(layer "B.Fab")
		)
		(fp_line
			(start -0.120396 0.3048)
			(end -0.120396 0.2794)
			(stroke
				(width 0.1)
				(type default)
			)
			(layer "B.Fab")
		)
		(fp_line
			(start -0.120396 0.2794)
			(end 0.12065 0.2794)
			(stroke
				(width 0.1)
				(type default)
			)
			(layer "B.Fab")
		)
		(fp_line
			(start -0.12065 -0.2794)
			(end -0.12065 -0.3048)
			(stroke
				(width 0.1)
				(type default)
			)
			(layer "B.Fab")
		)
		(fp_line
			(start -0.12065 -0.3048)
			(end -0.67945 -0.3048)
			(stroke
				(width 0.1)
				(type default)
			)
			(layer "B.Fab")
		)
		(fp_line
			(start -0.67945 0.3048)
			(end -0.120396 0.3048)
			(stroke
				(width 0.1)
				(type default)
			)
			(layer "B.Fab")
		)
		(fp_line
			(start -0.67945 -0.3048)
			(end -0.67945 0.3048)
			(stroke
				(width 0.1)
				(type default)
			)
			(layer "B.Fab")
		)
		(pad "1" smd circle
			(at 0.40005 0)
			(size 0 0)
			(layers "B.Cu" "B.Mask" "B.Paste")
			(net "PD_CHD_CPU0_DIMM_SAA")
		)
		(pad "2" smd circle
			(at -0.40005 0)
			(size 0 0)
			(layers "B.Cu" "B.Mask" "B.Paste")
			(net "GND")
		)
	)
	(footprint ""
		(layer "B.Cu")
		(at 67.417442 -387.768592 180)
		(property "Reference" "C264"
			(at 0 0 0)
			(layer "B.SilkS")
			(hide yes)
			(effects
				(font
					(size 1.27 1.27)
				)
				(justify mirror)
			)
		)
		(property "Value" ""
			(at 0 0 0)
			(layer "B.Fab")
			(effects
				(font
					(size 1.27 1.27)
				)
				(justify mirror)
			)
		)
		(duplicate_pad_numbers_are_jumpers no)
		(fp_line
			(start 0.299974 0.150114)
			(end 0.299974 -0.150114)
			(stroke
				(width 0.1)
				(type default)
			)
			(layer "B.Fab")
		)
		(fp_line
			(start 0.299974 -0.150114)
			(end -0.299974 -0.150114)
			(stroke
				(width 0.1)
				(type default)
			)
			(layer "B.Fab")
		)
		(fp_line
			(start -0.299974 0.150114)
			(end 0.299974 0.150114)
			(stroke
				(width 0.1)
				(type default)
			)
			(layer "B.Fab")
		)
		(fp_line
			(start -0.299974 -0.150114)
			(end -0.299974 0.150114)
			(stroke
				(width 0.1)
				(type default)
			)
			(layer "B.Fab")
		)
		(pad "1" smd rect
			(at 0.2667 0)
			(size 0.3048 0.381)
			(layers "B.Cu" "B.Mask" "B.Paste")
			(net "P0V9_CPU1_RT0_2A")
		)
		(pad "2" smd rect
			(at -0.2667 0)
			(size 0.3048 0.381)
			(layers "B.Cu" "B.Mask" "B.Paste")
			(net "GND")
		)
	)
)
